# T6G (Grand Teton) — schematic netlist excerpt (pin names and nets, part order shuffled) for the footprints in the layout excerpt that follows; sources: Cadence DE-HDL packaged netlist, KiCad conversion of 04192023_DAF0TMB3IC0_F0TG_MB_C_brd_V02_OCP.brd

PC163_6  Q_CAP  22UF 4V 20% X6S  pkg C0805  page 196 : A = PVDDCR_CPU0_P0 ; B = GND
PR6548  Q_RES  0 5% CHIP  pkg 0402LF  page 364 : A = P0V9_RETIMER_CPU1_TEMP1_R ; B = GND
C431  Q_CAP  10UF 6.3V 20% X6S  pkg C0402  page 345 : A = P0V9_CPU1_RT2_2A ; B = GND

(kicad_pcb
	(version 20260206)
	(generator "pcbnew")
	(generator_version "10.0")
	(general
		(thickness 1.6)
		(legacy_teardrops no)
	)
	(paper "A4")
	(title_block
		(title "04192023_DAF0TMB3IC0_F0TG_MB_C_brd_V02_OCP.brd")
		(comment 1 "Grand Teton / footprints 5316-5318 of 8354")
	)
	(layers
		(0 "F.Cu" signal "TOP")
		(4 "In1.Cu" signal "GND")
		(6 "In2.Cu" signal "IN1")
		(8 "In3.Cu" signal "GND1")
		(10 "In4.Cu" signal "IN2")
		(12 "In5.Cu" signal "GND2")
		(14 "In6.Cu" signal "IN3")
		(16 "In7.Cu" signal "GND3")
		(18 "In8.Cu" signal "VCC")
		(20 "In9.Cu" signal "VCC1")
		(22 "In10.Cu" signal "GND4")
		(24 "In11.Cu" signal "IN4")
		(26 "In12.Cu" signal "GND5")
		(28 "In13.Cu" signal "IN5")
		(30 "In14.Cu" signal "GND6")
		(32 "In15.Cu" signal "IN6")
		(34 "In16.Cu" signal "GND7")
		(2 "B.Cu" signal "BOTTOM")
		(9 "F.Adhes" user "F.Adhesive")
		(11 "B.Adhes" user "B.Adhesive")
		(13 "F.Paste" user "Package Geometry/Pastemask Top")
		(15 "B.Paste" user "Package Geometry/Pastemask Bottom")
		(5 "F.SilkS" user "Ref Des/Silkscreen Top")
		(7 "B.SilkS" user "Ref Des/Silkscreen Bottom")
		(1 "F.Mask" user "Board Geometry/Soldermask Top")
		(3 "B.Mask" user "Board Geometry/Soldermask Bottom")
		(17 "Dwgs.User" user "User.Drawings")
		(19 "Cmts.User" user "User.Comments")
		(21 "Eco1.User" user "User.Eco1")
		(23 "Eco2.User" user "User.Eco2")
		(25 "Edge.Cuts" user "Board Geometry/Outline")
		(27 "Margin" user)
		(31 "F.CrtYd" user "Package Geometry/Place Bound Top")
		(29 "B.CrtYd" user "Package Geometry/Place Bound Bottom")
		(35 "F.Fab" user "Ref Des/Assembly Top")
		(33 "B.Fab" user "Ref Des/Assembly Bottom")
	)
	(footprint ""
		(layer "B.Cu")
		(at 165.018974 -390.560052 90)
		(property "Reference" "C431"
			(at 0 0 90)
			(layer "B.SilkS")
			(hide yes)
			(effects
				(font
					(size 1.27 1.27)
				)
				(justify mirror)
			)
		)
		(property "Value" ""
			(at 0 0 90)
			(layer "B.Fab")
			(effects
				(font
					(size 1.27 1.27)
				)
				(justify mirror)
			)
		)
		(duplicate_pad_numbers_are_jumpers no)
		(fp_line
			(start 0.7874 -0.4064)
			(end -0.7874 -0.4064)
			(stroke
				(width 0.1524)
				(type default)
			)
			(layer "B.SilkS")
		)
		(fp_line
			(start -0.7874 -0.4064)
			(end -0.7874 0.4064)
			(stroke
				(width 0.1524)
				(type default)
			)
			(layer "B.SilkS")
		)
		(fp_line
			(start 0.7874 0.4064)
			(end 0.7874 -0.4064)
			(stroke
				(width 0.1524)
				(type default)
			)
			(layer "B.SilkS")
		)
		(fp_line
			(start -0.7874 0.4064)
			(end 0.7874 0.4064)
			(stroke
				(width 0.1524)
				(type default)
			)
			(layer "B.SilkS")
		)
		(fp_line
			(start 0.67945 -0.305054)
			(end 0.12065 -0.305054)
			(stroke
				(width 0.1)
				(type default)
			)
			(layer "B.Fab")
		)
		(fp_line
			(start 0.12065 -0.305054)
			(end 0.12065 -0.2794)
			(stroke
				(width 0.1)
				(type default)
			)
			(layer "B.Fab")
		)
		(fp_line
			(start -0.12065 -0.3048)
			(end -0.67945 -0.3048)
			(stroke
				(width 0.1)
				(type default)
			)
			(layer "B.Fab")
		)
		(fp_line
			(start -0.67945 -0.3048)
			(end -0.67945 0.3048)
			(stroke
				(width 0.1)
				(type default)
			)
			(layer "B.Fab")
		)
		(fp_line
			(start 0.12065 -0.2794)
			(end -0.12065 -0.2794)
			(stroke
				(width 0.1)
				(type default)
			)
			(layer "B.Fab")
		)
		(fp_line
			(start -0.12065 -0.2794)
			(end -0.12065 -0.3048)
			(stroke
				(width 0.1)
				(type default)
			)
			(layer "B.Fab")
		)
		(fp_line
			(start 0.12065 0.2794)
			(end 0.12065 0.3048)
			(stroke
				(width 0.1)
				(type default)
			)
			(layer "B.Fab")
		)
		(fp_line
			(start -0.120396 0.2794)
			(end 0.12065 0.2794)
			(stroke
				(width 0.1)
				(type default)
			)
			(layer "B.Fab")
		)
		(fp_line
			(start 0.67945 0.3048)
			(end 0.67945 -0.305054)
			(stroke
				(width 0.1)
				(type default)
			)
			(layer "B.Fab")
		)
		(fp_line
			(start 0.12065 0.3048)
			(end 0.67945 0.3048)
			(stroke
				(width 0.1)
				(type default)
			)
			(layer "B.Fab")
		)
		(fp_line
			(start -0.120396 0.3048)
			(end -0.120396 0.2794)
			(stroke
				(width 0.1)
				(type default)
			)
			(layer "B.Fab")
		)
		(fp_line
			(start -0.67945 0.3048)
			(end -0.120396 0.3048)
			(stroke
				(width 0.1)
				(type default)
			)
			(layer "B.Fab")
		)
		(pad "1" smd circle
			(at 0.40005 0 270)
			(size 0 0)
			(layers "B.Cu" "B.Mask" "B.Paste")
			(net "P0V9_CPU1_RT2_2A")
		)
		(pad "2" smd circle
			(at -0.40005 0 270)
			(size 0 0)
			(layers "B.Cu" "B.Mask" "B.Paste")
			(net "GND")
		)
	)
	(footprint ""
		(layer "B.Cu")
		(at 9.838182 -409.472384 90)
		(property "Reference" "PR6548"
			(at 0 0 90)
			(layer "B.SilkS")
			(hide yes)
			(effects
				(font
					(size 1.27 1.27)
				)
				(justify mirror)
			)
		)
		(property "Value" ""
			(at 0 0 90)
			(layer "B.Fab")
			(effects
				(font
					(size 1.27 1.27)
				)
				(justify mirror)
			)
		)
		(duplicate_pad_numbers_are_jumpers no)
		(fp_line
			(start 0.7874 -0.4064)
			(end -0.7874 -0.4064)
			(stroke
				(width 0.1524)
				(type default)
			)
			(layer "B.SilkS")
		)
		(fp_line
			(start -0.7874 -0.4064)
			(end -0.7874 0.4064)
			(stroke
				(width 0.1524)
				(type default)
			)
			(layer "B.SilkS")
		)
		(fp_line
			(start 0.7874 0.4064)
			(end 0.7874 -0.4064)
			(stroke
				(width 0.1524)
				(type default)
			)
			(layer "B.SilkS")
		)
		(fp_line
			(start -0.7874 0.4064)
			(end 0.7874 0.4064)
			(stroke
				(width 0.1524)
				(type default)
			)
			(layer "B.SilkS")
		)
		(fp_line
			(start 0.67945 -0.305054)
			(end 0.12065 -0.305054)
			(stroke
				(width 0.1)
				(type default)
			)
			(layer "B.Fab")
		)
		(fp_line
			(start 0.12065 -0.305054)
			(end 0.12065 -0.2794)
			(stroke
				(width 0.1)
				(type default)
			)
			(layer "B.Fab")
		)
		(fp_line
			(start -0.12065 -0.3048)
			(end -0.67945 -0.3048)
			(stroke
				(width 0.1)
				(type default)
			)
			(layer "B.Fab")
		)
		(fp_line
			(start -0.67945 -0.3048)
			(end -0.67945 0.3048)
			(stroke
				(width 0.1)
				(type default)
			)
			(layer "B.Fab")
		)
		(fp_line
			(start 0.12065 -0.2794)
			(end -0.12065 -0.2794)
			(stroke
				(width 0.1)
				(type default)
			)
			(layer "B.Fab")
		)
		(fp_line
			(start -0.12065 -0.2794)
			(end -0.12065 -0.3048)
			(stroke
				(width 0.1)
				(type default)
			)
			(layer "B.Fab")
		)
		(fp_line
			(start 0.12065 0.2794)
			(end 0.12065 0.3048)
			(stroke
				(width 0.1)
				(type default)
			)
			(layer "B.Fab")
		)
		(fp_line
			(start -0.120396 0.2794)
			(end 0.12065 0.2794)
			(stroke
				(width 0.1)
				(type default)
			)
			(layer "B.Fab")
		)
		(fp_line
			(start 0.67945 0.3048)
			(end 0.67945 -0.305054)
			(stroke
				(width 0.1)
				(type default)
			)
			(layer "B.Fab")
		)
		(fp_line
			(start 0.12065 0.3048)
			(end 0.67945 0.3048)
			(stroke
				(width 0.1)
				(type default)
			)
			(layer "B.Fab")
		)
		(fp_line
			(start -0.120396 0.3048)
			(end -0.120396 0.2794)
			(stroke
				(width 0.1)
				(type default)
			)
			(layer "B.Fab")
		)
		(fp_line
			(start -0.67945 0.3048)
			(end -0.120396 0.3048)
			(stroke
				(width 0.1)
				(type default)
			)
			(layer "B.Fab")
		)
		(pad "1" smd circle
			(at 0.40005 0 270)
			(size 0 0)
			(layers "B.Cu" "B.Mask" "B.Paste")
			(net "P0V9_RETIMER_CPU1_TEMP1_R")
		)
		(pad "2" smd circle
			(at -0.40005 0 270)
			(size 0 0)
			(layers "B.Cu" "B.Mask" "B.Paste")
			(net "GND")
		)
	)
	(footprint ""
		(layer "B.Cu")
		(at 343.39022 -169.787062 90)
		(property "Reference" "PC163_6"
			(at 0 0 90)
			(layer "B.SilkS")
			(hide yes)
			(effects
				(font
					(size 1.27 1.27)
				)
				(justify mirror)
			)
		)
		(property "Value" ""
			(at 0 0 90)
			(layer "B.Fab")
			(effects
				(font
					(size 1.27 1.27)
				)
				(justify mirror)
			)
		)
		(duplicate_pad_numbers_are_jumpers no)
		(fp_line
			(start 1.524 -0.762)
			(end -1.524 -0.762)
			(stroke
				(width 0.1524)
				(type default)
			)
			(layer "B.SilkS")
		)
		(fp_line
			(start -1.524 -0.762)
			(end -1.524 0.762)
			(stroke
				(width 0.1524)
				(type default)
			)
			(layer "B.SilkS")
		)
		(fp_line
			(start 1.524 0.762)
			(end 1.524 -0.762)
			(stroke
				(width 0.1524)
				(type default)
			)
			(layer "B.SilkS")
		)
		(fp_line
			(start -1.524 0.762)
			(end 1.524 0.762)
			(stroke
				(width 0.1524)
				(type default)
			)
			(layer "B.SilkS")
		)
		(fp_line
			(start 1.1049 -0.724916)
			(end 1.1049 0.724916)
			(stroke
				(width 0.1)
				(type default)
			)
			(layer "B.Fab")
		)
		(fp_line
			(start -1.1049 -0.724916)
			(end 1.1049 -0.724916)
			(stroke
				(width 0.1)
				(type default)
			)
			(layer "B.Fab")
		)
		(fp_line
			(start 1.1049 0.724916)
			(end -1.1049 0.724916)
			(stroke
				(width 0.1)
				(type default)
			)
			(layer "B.Fab")
		)
		(fp_line
			(start -1.1049 0.724916)
			(end -1.1049 -0.724916)
			(stroke
				(width 0.1)
				(type default)
			)
			(layer "B.Fab")
		)
		(pad "1" smd rect
			(at 0.889 0 90)
			(size 1.016 1.27)
			(layers "B.Cu" "B.Mask" "B.Paste")
			(net "PVDDCR_CPU0_P0")
		)
		(pad "2" smd rect
			(at -0.889 0 90)
			(size 1.016 1.27)
			(layers "B.Cu" "B.Mask" "B.Paste")
			(net "GND")
		)
	)
)
